(kicad_pcb
	(version 20260206)
	(generator "pcbnew")
	(generator_version "10.0")
	(general
		(thickness 1.6)
		(legacy_teardrops no)
	)
	(paper "A4")
	(title_block
		(title "timecard-production-celestica-r4006 — R4006-B0001-02_R01.brd")
		(comment 1 "Time Appliance Project (Time Card) / footprints 135-144 of 1113")
	)
	(layers
		(0 "F.Cu" signal "TOP")
		(4 "In1.Cu" signal "L02_GND1")
		(6 "In2.Cu" signal "L03_SIG1")
		(8 "In3.Cu" signal "L04_GND2")
		(10 "In4.Cu" signal "L05_VCC1")
		(12 "In5.Cu" signal "L06_VCC2")
		(14 "In6.Cu" signal "L07_GND3")
		(16 "In7.Cu" signal "L08_SIG2")
		(18 "In8.Cu" signal "L09_GND4")
		(2 "B.Cu" signal "BOTTOM")
		(9 "F.Adhes" user "F.Adhesive")
		(11 "B.Adhes" user "B.Adhesive")
		(13 "F.Paste" user "Package Geometry/Pastemask Top")
		(15 "B.Paste" user "Package Geometry/Pastemask Bottom")
		(5 "F.SilkS" user "Ref Des/Silkscreen Top")
		(7 "B.SilkS" user "Ref Des/Silkscreen Bottom")
		(1 "F.Mask" user "Board Geometry/Soldermask Top")
		(3 "B.Mask" user "Board Geometry/Soldermask Bottom")
		(17 "Dwgs.User" user "User.Drawings")
		(19 "Cmts.User" user "User.Comments")
		(21 "Eco1.User" user "User.Eco1")
		(23 "Eco2.User" user "User.Eco2")
		(25 "Edge.Cuts" user "Board Geometry/Outline")
		(27 "Margin" user)
		(31 "F.CrtYd" user "Package Geometry/Place Bound Top")
		(29 "B.CrtYd" user "Package Geometry/Place Bound Bottom")
		(35 "F.Fab" user "Ref Des/Assembly Top")
		(33 "B.Fab" user "Ref Des/Assembly Bottom")
	)
	(footprint ""
		(layer "F.Cu")
		(at 127.889 -62.8396)
		(property "Reference" "C183"
			(at 1.143 4.83997 0)
			(unlocked yes)
			(layer "F.SilkS")
			(effects
				(font
					(size 0.7874 0.5842)
					(thickness 0.1524)
				)
			)
		)
		(property "Value" "VAL*"
			(at 0.0762 2.067306 0)
			(unlocked yes)
			(layer "F.Fab")
			(hide yes)
			(effects
				(font
					(size 0.7874 0.5842)
					(thickness 0.1524)
				)
			)
		)
		(property "Device Type" "CAPACITOR-G105-0B104-EK,0.1UF,A"
			(at 0.0508 1.127506 0)
			(unlocked yes)
			(layer "F.Fab")
			(hide yes)
			(effects
				(font
					(size 0.7874 0.5842)
					(thickness 0.1524)
				)
			)
		)
		(property "User Part Number" "PARTNUM*"
			(at 0.1016 4.023106 0)
			(unlocked yes)
			(layer "Cmts.User")
			(hide yes)
			(effects
				(font
					(size 0.7874 0.5842)
					(thickness 0.1524)
				)
			)
		)
		(property "Tolerance" "TOL*"
			(at 0.0762 3.032506 0)
			(unlocked yes)
			(layer "Cmts.User")
			(hide yes)
			(effects
				(font
					(size 0.7874 0.5842)
					(thickness 0.1524)
				)
			)
		)
		(duplicate_pad_numbers_are_jumpers no)
		(fp_line
			(start -1.143 -0.5588)
			(end -1.143 0.5588)
			(stroke
				(width 0.1)
				(type default)
			)
			(layer "F.SilkS")
		)
		(fp_line
			(start -1.143 0.5588)
			(end 1.143 0.5588)
			(stroke
				(width 0.1)
				(type default)
			)
			(layer "F.SilkS")
		)
		(fp_line
			(start 1.143 -0.5588)
			(end -1.143 -0.5588)
			(stroke
				(width 0.1)
				(type default)
			)
			(layer "F.SilkS")
		)
		(fp_line
			(start 1.143 0.5588)
			(end 1.143 -0.5588)
			(stroke
				(width 0.1)
				(type default)
			)
			(layer "F.SilkS")
		)
		(fp_rect
			(start 1.143 -0.5588)
			(end -1.143 0.5588)
			(stroke
				(width 0)
				(type default)
			)
			(fill no)
			(layer "F.CrtYd")
		)
		(fp_line
			(start -0.508 -0.3048)
			(end -0.508 0.3048)
			(stroke
				(width 0.1)
				(type default)
			)
			(layer "F.Fab")
		)
		(fp_line
			(start -0.508 0.3048)
			(end 0.508 0.3048)
			(stroke
				(width 0.1)
				(type default)
			)
			(layer "F.Fab")
		)
		(fp_line
			(start 0.508 -0.3048)
			(end -0.508 -0.3048)
			(stroke
				(width 0.1)
				(type default)
			)
			(layer "F.Fab")
		)
		(fp_line
			(start 0.508 0.3048)
			(end 0.508 -0.3048)
			(stroke
				(width 0.1)
				(type default)
			)
			(layer "F.Fab")
		)
		(pad "1" smd rect
			(at -0.5334 0)
			(size 0.7112 0.6096)
			(layers "F.Cu" "F.Mask" "F.Paste")
			(net "XP3R3V")
		)
		(pad "2" smd rect
			(at 0.5334 0)
			(size 0.7112 0.6096)
			(layers "F.Cu" "F.Mask" "F.Paste")
			(net "SG")
		)
		(zone
			(layer "F.Cu")
			(hatch none 0.5)
			(connect_pads
				(clearance 0)
			)
			(min_thickness 0.25)
			(keepout
				(tracks allowed)
				(vias not_allowed)
				(pads allowed)
				(copperpour not_allowed)
				(footprints allowed)
			)
			(placement
				(enabled no)
				(sheetname "")
			)
			(fill
				(thermal_gap 0.5)
				(thermal_bridge_width 0.5)
				(island_removal_mode 0)
			)
			(polygon
				(pts
					(xy 127.9652 -63.1444) (xy 127.8128 -63.1444) (xy 127.8128 -62.5348) (xy 127.9652 -62.5348)
				)
			)
		)
	)
	(footprint ""
		(layer "F.Cu")
		(at 16.256 -70.866 180)
		(property "Reference" "R346"
			(at -0.381 1.73863 0)
			(unlocked yes)
			(layer "F.SilkS")
			(effects
				(font
					(size 0.7874 0.5842)
					(thickness 0.1524)
				)
			)
		)
		(property "Value" "VAL*"
			(at 0.02032 2.13233 180)
			(unlocked yes)
			(layer "F.Fab")
			(hide yes)
			(effects
				(font
					(size 0.7874 0.5842)
					(thickness 0.1524)
				)
			)
		)
		(property "Tolerance" "TOL*"
			(at 0.044704 3.05435 180)
			(unlocked yes)
			(layer "Cmts.User")
			(hide yes)
			(effects
				(font
					(size 0.7874 0.5842)
					(thickness 0.1524)
				)
			)
		)
		(property "User Part Number" "PARTNUM*"
			(at 0.02032 4.024884 180)
			(unlocked yes)
			(layer "Cmts.User")
			(hide yes)
			(effects
				(font
					(size 0.7874 0.5842)
					(thickness 0.1524)
				)
			)
		)
		(property "Device Type" "RESISTOR-G155-100R0-J0,0OHM,-"
			(at 0.008382 1.210564 180)
			(unlocked yes)
			(layer "F.Fab")
			(hide yes)
			(effects
				(font
					(size 0.7874 0.5842)
					(thickness 0.1524)
				)
			)
		)
		(duplicate_pad_numbers_are_jumpers no)
		(fp_line
			(start 1.143 0.5588)
			(end 1.143 -0.5588)
			(stroke
				(width 0.1)
				(type default)
			)
			(layer "F.SilkS")
		)
		(fp_line
			(start 1.143 -0.5588)
			(end -1.143 -0.5588)
			(stroke
				(width 0.1)
				(type default)
			)
			(layer "F.SilkS")
		)
		(fp_line
			(start -1.143 0.5588)
			(end 1.143 0.5588)
			(stroke
				(width 0.1)
				(type default)
			)
			(layer "F.SilkS")
		)
		(fp_line
			(start -1.143 -0.5588)
			(end -1.143 0.5588)
			(stroke
				(width 0.1)
				(type default)
			)
			(layer "F.SilkS")
		)
		(fp_poly
			(pts
				(xy -1.143 0.5588) (xy 1.143 0.5588) (xy 1.143 -0.5588) (xy -1.143 -0.5588)
			)
			(stroke
				(width 0)
				(type default)
			)
			(fill no)
			(layer "F.CrtYd")
		)
		(fp_line
			(start 0.508 0.3048)
			(end 0.508 -0.3048)
			(stroke
				(width 0.1)
				(type default)
			)
			(layer "F.Fab")
		)
		(fp_line
			(start 0.508 -0.3048)
			(end -0.508 -0.3048)
			(stroke
				(width 0.1)
				(type default)
			)
			(layer "F.Fab")
		)
		(fp_line
			(start -0.508 0.3048)
			(end 0.508 0.3048)
			(stroke
				(width 0.1)
				(type default)
			)
			(layer "F.Fab")
		)
		(fp_line
			(start -0.508 -0.3048)
			(end -0.508 0.3048)
			(stroke
				(width 0.1)
				(type default)
			)
			(layer "F.Fab")
		)
		(pad "1" smd rect
			(at -0.5334 0 180)
			(size 0.7112 0.6096)
			(layers "F.Cu" "F.Mask" "F.Paste")
			(net "UNNAMED_8_ICP10100LGA10_I24_R_1")
		)
		(pad "2" smd rect
			(at 0.5334 0 180)
			(size 0.7112 0.6096)
			(layers "F.Cu" "F.Mask" "F.Paste")
			(net "SG")
		)
		(zone
			(layer "F.Cu")
			(hatch none 0.5)
			(connect_pads
				(clearance 0)
			)
			(min_thickness 0.25)
			(keepout
				(tracks allowed)
				(vias not_allowed)
				(pads allowed)
				(copperpour not_allowed)
				(footprints allowed)
			)
			(placement
				(enabled no)
				(sheetname "")
			)
			(fill
				(thermal_gap 0.5)
				(thermal_bridge_width 0.5)
				(island_removal_mode 0)
			)
			(polygon
				(pts
					(xy 16.3322 -71.1708) (xy 16.1798 -71.1708) (xy 16.1798 -70.5612) (xy 16.3322 -70.5612)
				)
			)
		)
		(zone
			(layer "F.Cu")
			(hatch none 0.5)
			(connect_pads
				(clearance 0)
			)
			(min_thickness 0.25)
			(keepout
				(tracks not_allowed)
				(vias allowed)
				(pads allowed)
				(copperpour not_allowed)
				(footprints allowed)
			)
			(placement
				(enabled no)
				(sheetname "")
			)
			(fill
				(thermal_gap 0.5)
				(thermal_bridge_width 0.5)
				(island_removal_mode 0)
			)
			(polygon
				(pts
					(xy 16.3322 -71.1708) (xy 16.1798 -71.1708) (xy 16.1798 -70.5612) (xy 16.3322 -70.5612)
				)
			)
		)
	)
	(footprint ""
		(layer "F.Cu")
		(at 16.1544 -74.041)
		(property "Reference" "TP24"
			(at -2.3876 -2.37363 0)
			(unlocked yes)
			(layer "F.SilkS")
			(effects
				(font
					(size 0.7874 0.5842)
					(thickness 0.1524)
				)
				(justify left)
			)
		)
		(property "Value" ""
			(at 0 0 0)
			(layer "F.Fab")
			(effects
				(font
					(size 1.27 1.27)
				)
			)
		)
		(property "Device Type" "TP_PIONT-TP010CT020B030_PTH-TPA"
			(at -1.341882 0.996696 0)
			(unlocked yes)
			(layer "F.Fab")
			(hide yes)
			(effects
				(font
					(size 0.7874 0.5842)
					(thickness 0.000001)
				)
				(justify left)
			)
		)
		(duplicate_pad_numbers_are_jumpers no)
		(fp_poly
			(pts
				(arc
					(start 0.889 0)
					(mid -0.889 0)
					(end 0.889 0)
				)
			)
			(stroke
				(width 0)
				(type default)
			)
			(fill no)
			(layer "B.CrtYd")
		)
		(fp_poly
			(pts
				(arc
					(start 0.889 0)
					(mid -0.889 0)
					(end 0.889 0)
				)
			)
			(stroke
				(width 0)
				(type default)
			)
			(fill no)
			(layer "F.CrtYd")
		)
		(pad "1" thru_hole circle
			(at 0 0)
			(size 0.508 0.508)
			(drill 0.254)
			(layers "*.Cu" "*.Mask")
			(remove_unused_layers no)
			(net "FPGA_IN_LM75B_INT1_N")
			(clearance 0.1016)
			(padstack
				(mode front_inner_back)
				(layer "Inner"
					(shape circle)
					(size 0.508 0.508)
					(clearance 0.1016)
				)
				(layer "B.Cu"
					(shape circle)
					(size 0.762 0.762)
					(clearance -0.0254)
				)
			)
		)
	)
	(footprint ""
		(layer "F.Cu")
		(at 14.351 -28.702)
		(property "Reference" "TP30"
			(at -0.22225 2.5654 90)
			(unlocked yes)
			(layer "F.SilkS")
			(effects
				(font
					(size 0.635 0.4064)
					(thickness 0.1524)
				)
				(justify left)
			)
		)
		(property "Value" ""
			(at 0 0 0)
			(layer "F.Fab")
			(effects
				(font
					(size 1.27 1.27)
				)
			)
		)
		(property "Device Type" "TP_PIONT-TP010CT020B030_PTH-TPA"
			(at -1.341882 0.996696 0)
			(unlocked yes)
			(layer "F.Fab")
			(hide yes)
			(effects
				(font
					(size 0.7874 0.5842)
					(thickness 0.000001)
				)
				(justify left)
			)
		)
		(duplicate_pad_numbers_are_jumpers no)
		(fp_poly
			(pts
				(arc
					(start 0.889 0)
					(mid -0.889 0)
					(end 0.889 0)
				)
			)
			(stroke
				(width 0)
				(type default)
			)
			(fill no)
			(layer "B.CrtYd")
		)
		(fp_poly
			(pts
				(arc
					(start 0.889 0)
					(mid -0.889 0)
					(end 0.889 0)
				)
			)
			(stroke
				(width 0)
				(type default)
			)
			(fill no)
			(layer "F.CrtYd")
		)
		(pad "1" thru_hole circle
			(at 0 0)
			(size 0.508 0.508)
			(drill 0.254)
			(layers "*.Cu" "*.Mask")
			(remove_unused_layers no)
			(net "SMA3_SIG_IN_BF_EN_N")
			(clearance 0.1016)
			(padstack
				(mode front_inner_back)
				(layer "Inner"
					(shape circle)
					(size 0.508 0.508)
					(clearance 0.1016)
				)
				(layer "B.Cu"
					(shape circle)
					(size 0.762 0.762)
					(clearance -0.0254)
				)
			)
		)
	)
	(footprint ""
		(layer "F.Cu")
		(at 145.2372 -100.711)
		(property "Reference" "TP37"
			(at 1.4224 0.15875 0)
			(unlocked yes)
			(layer "F.SilkS")
			(effects
				(font
					(size 0.635 0.4064)
					(thickness 0.1524)
				)
				(justify left)
			)
		)
		(property "Value" ""
			(at 0 0 0)
			(layer "F.Fab")
			(effects
				(font
					(size 1.27 1.27)
				)
			)
		)
		(property "Device Type" "TP_PIONT-TP010CT020B030_PTH-TPA"
			(at -1.341882 0.996696 0)
			(unlocked yes)
			(layer "F.Fab")
			(hide yes)
			(effects
				(font
					(size 0.7874 0.5842)
					(thickness 0.000001)
				)
				(justify left)
			)
		)
		(duplicate_pad_numbers_are_jumpers no)
		(fp_poly
			(pts
				(arc
					(start 0.889 0)
					(mid -0.889 0)
					(end 0.889 0)
				)
			)
			(stroke
				(width 0)
				(type default)
			)
			(fill no)
			(layer "B.CrtYd")
		)
		(fp_poly
			(pts
				(arc
					(start 0.889 0)
					(mid -0.889 0)
					(end 0.889 0)
				)
			)
			(stroke
				(width 0)
				(type default)
			)
			(fill no)
			(layer "F.CrtYd")
		)
		(pad "1" thru_hole circle
			(at 0 0)
			(size 0.508 0.508)
			(drill 0.254)
			(layers "*.Cu" "*.Mask")
			(remove_unused_layers no)
			(net "XP12R0V_A_FLTB")
			(clearance 0.1016)
			(padstack
				(mode front_inner_back)
				(layer "Inner"
					(shape circle)
					(size 0.508 0.508)
					(clearance 0.1016)
				)
				(layer "B.Cu"
					(shape circle)
					(size 0.762 0.762)
					(clearance -0.0254)
				)
			)
		)
	)
	(footprint ""
		(layer "F.Cu")
		(at 133.858 -70.866 -90)
		(property "Reference" "R179"
			(at -4.191 -1.05537 90)
			(unlocked yes)
			(layer "F.SilkS")
			(effects
				(font
					(size 0.7874 0.5842)
					(thickness 0.1524)
				)
			)
		)
		(property "Value" "VAL*"
			(at 0.02032 2.13233 270)
			(unlocked yes)
			(layer "F.Fab")
			(hide yes)
			(effects
				(font
					(size 0.7874 0.5842)
					(thickness 0.1524)
				)
			)
		)
		(property "Device Type" "RESISTOR-G155-14701-01,4.7KOHMA"
			(at 0.008382 1.210564 270)
			(unlocked yes)
			(layer "F.Fab")
			(hide yes)
			(effects
				(font
					(size 0.7874 0.5842)
					(thickness 0.1524)
				)
			)
		)
		(property "User Part Number" "PARTNUM*"
			(at 0.02032 4.024884 270)
			(unlocked yes)
			(layer "Cmts.User")
			(hide yes)
			(effects
				(font
					(size 0.7874 0.5842)
					(thickness 0.1524)
				)
			)
		)
		(property "Tolerance" "TOL*"
			(at 0.044704 3.05435 270)
			(unlocked yes)
			(layer "Cmts.User")
			(hide yes)
			(effects
				(font
					(size 0.7874 0.5842)
					(thickness 0.1524)
				)
			)
		)
		(duplicate_pad_numbers_are_jumpers no)
		(fp_line
			(start -1.143 0.5588)
			(end 1.143 0.5588)
			(stroke
				(width 0.1)
				(type default)
			)
			(layer "F.SilkS")
		)
		(fp_line
			(start 1.143 0.5588)
			(end 1.143 -0.5588)
			(stroke
				(width 0.1)
				(type default)
			)
			(layer "F.SilkS")
		)
		(fp_line
			(start -1.143 -0.5588)
			(end -1.143 0.5588)
			(stroke
				(width 0.1)
				(type default)
			)
			(layer "F.SilkS")
		)
		(fp_line
			(start 1.143 -0.5588)
			(end -1.143 -0.5588)
			(stroke
				(width 0.1)
				(type default)
			)
			(layer "F.SilkS")
		)
		(fp_rect
			(start -1.143 0.5588)
			(end 1.143 -0.5588)
			(stroke
				(width 0)
				(type default)
			)
			(fill no)
			(layer "F.CrtYd")
		)
		(fp_line
			(start -0.508 0.3048)
			(end 0.508 0.3048)
			(stroke
				(width 0.1)
				(type default)
			)
			(layer "F.Fab")
		)
		(fp_line
			(start 0.508 0.3048)
			(end 0.508 -0.3048)
			(stroke
				(width 0.1)
				(type default)
			)
			(layer "F.Fab")
		)
		(fp_line
			(start -0.508 -0.3048)
			(end -0.508 0.3048)
			(stroke
				(width 0.1)
				(type default)
			)
			(layer "F.Fab")
		)
		(fp_line
			(start 0.508 -0.3048)
			(end -0.508 -0.3048)
			(stroke
				(width 0.1)
				(type default)
			)
			(layer "F.Fab")
		)
		(pad "1" smd rect
			(at -0.5334 0 270)
			(size 0.7112 0.6096)
			(layers "F.Cu" "F.Mask" "F.Paste")
			(net "XP3R3V")
		)
		(pad "2" smd rect
			(at 0.5334 0 270)
			(size 0.7112 0.6096)
			(layers "F.Cu" "F.Mask" "F.Paste")
			(net "XP1R8V_PG_R")
		)
		(zone
			(layer "F.Cu")
			(hatch none 0.5)
			(connect_pads
				(clearance 0)
			)
			(min_thickness 0.25)
			(keepout
				(tracks allowed)
				(vias not_allowed)
				(pads allowed)
				(copperpour not_allowed)
				(footprints allowed)
			)
			(placement
				(enabled no)
				(sheetname "")
			)
			(fill
				(thermal_gap 0.5)
				(thermal_bridge_width 0.5)
				(island_removal_mode 0)
			)
			(polygon
				(pts
					(xy 133.5532 -70.9422) (xy 133.5532 -70.7898) (xy 134.1628 -70.7898) (xy 134.1628 -70.9422)
				)
			)
		)
	)
	(footprint ""
		(layer "F.Cu")
		(at 58.313828 -12.425172)
		(property "Reference" "TP48"
			(at -0.986028 -1.505458 0)
			(unlocked yes)
			(layer "F.SilkS")
			(effects
				(font
					(size 0.7874 0.5842)
					(thickness 0.1524)
				)
				(justify left)
			)
		)
		(property "Value" ""
			(at 0 0 0)
			(layer "F.Fab")
			(effects
				(font
					(size 1.27 1.27)
				)
			)
		)
		(property "Device Type" "TP_PIONT-TP010CT020B030_PTH-TPA"
			(at -1.341882 0.996696 0)
			(unlocked yes)
			(layer "F.Fab")
			(hide yes)
			(effects
				(font
					(size 0.7874 0.5842)
					(thickness 0.000001)
				)
				(justify left)
			)
		)
		(duplicate_pad_numbers_are_jumpers no)
		(fp_poly
			(pts
				(arc
					(start 0.889 0)
					(mid -0.889 0)
					(end 0.889 0)
				)
			)
			(stroke
				(width 0)
				(type default)
			)
			(fill no)
			(layer "B.CrtYd")
		)
		(fp_poly
			(pts
				(arc
					(start 0.889 0)
					(mid -0.889 0)
					(end 0.889 0)
				)
			)
			(stroke
				(width 0)
				(type default)
			)
			(fill no)
			(layer "F.CrtYd")
		)
		(pad "1" thru_hole circle
			(at 0 0)
			(size 0.508 0.508)
			(drill 0.254)
			(layers "*.Cu" "*.Mask")
			(remove_unused_layers no)
			(net "PCIE_CONN_PERST_N")
			(clearance 0.1016)
			(padstack
				(mode front_inner_back)
				(layer "Inner"
					(shape circle)
					(size 0.508 0.508)
					(clearance 0.1016)
				)
				(layer "B.Cu"
					(shape circle)
					(size 0.762 0.762)
					(clearance -0.0254)
				)
			)
		)
	)
	(footprint ""
		(layer "F.Cu")
		(at 22.225 -75.057)
		(property "Reference" "TP7"
			(at 0 0 0)
			(layer "F.SilkS")
			(hide yes)
			(effects
				(font
					(size 1.27 1.27)
				)
			)
		)
		(property "Value" ""
			(at 0 0 0)
			(layer "F.Fab")
			(effects
				(font
					(size 1.27 1.27)
				)
			)
		)
		(property "Device Type" "TP_PIONT-TP010CT020B030_PTH-TPA"
			(at -1.341882 0.996696 0)
			(unlocked yes)
			(layer "F.Fab")
			(hide yes)
			(effects
				(font
					(size 0.7874 0.5842)
					(thickness 0.1524)
				)
				(justify left)
			)
		)
		(duplicate_pad_numbers_are_jumpers no)
		(fp_poly
			(pts
				(arc
					(start 0.889 0)
					(mid -0.889 0)
					(end 0.889 0)
				)
			)
			(stroke
				(width 0)
				(type default)
			)
			(fill no)
			(layer "B.CrtYd")
		)
		(fp_poly
			(pts
				(arc
					(start 0.889 0)
					(mid -0.889 0)
					(end 0.889 0)
				)
			)
			(stroke
				(width 0)
				(type default)
			)
			(fill no)
			(layer "F.CrtYd")
		)
		(pad "1" thru_hole circle
			(at 0 0)
			(size 0.508 0.508)
			(drill 0.254)
			(layers "*.Cu" "*.Mask")
			(remove_unused_layers no)
			(net "UNNAMED_524_FT4232HLREELQFP64_2")
			(clearance 0.1016)
			(padstack
				(mode front_inner_back)
				(layer "Inner"
					(shape circle)
					(size 0.508 0.508)
					(clearance 0.1016)
				)
				(layer "B.Cu"
					(shape circle)
					(size 0.762 0.762)
					(clearance -0.0254)
				)
			)
		)
	)
	(footprint ""
		(layer "F.Cu")
		(at 36.83 -141.478)
		(property "Reference" "SP20"
			(at 0 0 0)
			(layer "F.SilkS")
			(hide yes)
			(effects
				(font
					(size 1.27 1.27)
				)
			)
		)
		(property "Value" ""
			(at 0 0 0)
			(layer "F.Fab")
			(effects
				(font
					(size 1.27 1.27)
				)
			)
		)
		(duplicate_pad_numbers_are_jumpers no)
	)
	(footprint ""
		(layer "F.Cu")
		(at 49.657 -126.238)
		(property "Reference" "SP68"
			(at 0 0 0)
			(layer "F.SilkS")
			(hide yes)
			(effects
				(font
					(size 1.27 1.27)
				)
			)
		)
		(property "Value" ""
			(at 0 0 0)
			(layer "F.Fab")
			(effects
				(font
					(size 1.27 1.27)
				)
			)
		)
		(duplicate_pad_numbers_are_jumpers no)
	)
)
